(kicad_pcb
	(version 20260206)
	(generator "pcbnew")
	(generator_version "10.0")
	(general
		(thickness 1.6)
		(legacy_teardrops no)
	)
	(paper "A4")
	(title_block
		(title "Wiwynn_Tioga_Pass_MB.brd")
		(comment 1 "Tioga Pass / footprint 190 of 4770 (U2D1), pads 1229-1322 of 3647")
	)
	(layers
		(0 "F.Cu" signal "TOP")
		(4 "In1.Cu" signal "L2GND")
		(6 "In2.Cu" signal "L3")
		(8 "In3.Cu" signal "L4GND")
		(10 "In4.Cu" signal "L5")
		(12 "In5.Cu" signal "L6GND")
		(14 "In6.Cu" signal "L7VCC")
		(16 "In7.Cu" signal "L8VCC")
		(18 "In8.Cu" signal "L9GND")
		(20 "In9.Cu" signal "L10")
		(22 "In10.Cu" signal "L11GND")
		(24 "In11.Cu" signal "L12")
		(26 "In12.Cu" signal "L13GND")
		(2 "B.Cu" signal "BOTTOM")
		(9 "F.Adhes" user "F.Adhesive")
		(11 "B.Adhes" user "B.Adhesive")
		(13 "F.Paste" user "Package Geometry/Pastemask Top")
		(15 "B.Paste" user "Package Geometry/Pastemask Bottom")
		(5 "F.SilkS" user "Ref Des/Silkscreen Top")
		(7 "B.SilkS" user "Ref Des/Silkscreen Bottom")
		(1 "F.Mask" user "Board Geometry/Soldermask Top")
		(3 "B.Mask" user "Board Geometry/Soldermask Bottom")
		(17 "Dwgs.User" user "User.Drawings")
		(19 "Cmts.User" user "User.Comments")
		(21 "Eco1.User" user "User.Eco1")
		(23 "Eco2.User" user "User.Eco2")
		(25 "Edge.Cuts" user "Board Geometry/Outline")
		(27 "Margin" user)
		(31 "F.CrtYd" user "Package Geometry/Place Bound Top")
		(29 "B.CrtYd" user "Package Geometry/Place Bound Bottom")
		(35 "F.Fab" user "Ref Des/Assembly Top")
		(33 "B.Fab" user "Ref Des/Assembly Bottom")
	)
	(footprint ""
		(layer "F.Cu")
		(at 104.99979 -76.550012 180)
		(property "Reference" "U2D1"
			(at 25.19299 30.484318 0)
			(unlocked yes)
			(layer "F.SilkS")
			(effects
				(font
					(size 0.7874 0.5842)
					(thickness 0.1524)
				)
			)
		)
		(property "Value" ""
			(at 0 0 180)
			(layer "F.Fab")
			(effects
				(font
					(size 1.27 1.27)
				)
			)
		)
		(duplicate_pad_numbers_are_jumpers no)
		(pad "BW66" smd circle
			(at 20.080478 1.824228)
			(size 0.4318 0.4318)
			(layers "F.Cu" "F.Mask" "F.Paste")
			(net "PVCCIN_CPU1")
		)
		(pad "BW68" smd circle
			(at 21.797518 1.824228)
			(size 0.4318 0.4318)
			(layers "F.Cu" "F.Mask" "F.Paste")
			(net "PVCCIN_CPU1")
		)
		(pad "BW70" smd circle
			(at 23.514558 1.824228)
			(size 0.4318 0.4318)
			(layers "F.Cu" "F.Mask" "F.Paste")
			(net "PVCCIN_CPU1")
		)
		(pad "BW72" smd circle
			(at 25.231598 1.824228)
			(size 0.4318 0.4318)
			(layers "F.Cu" "F.Mask" "F.Paste")
			(net "GND")
		)
		(pad "BW74" smd circle
			(at 26.948384 1.824228)
			(size 0.4318 0.4318)
			(layers "F.Cu" "F.Mask" "F.Paste")
			(net "GND")
		)
		(pad "BW76" smd circle
			(at 28.665424 1.824228)
			(size 0.4318 0.4318)
			(layers "F.Cu" "F.Mask" "F.Paste")
			(net "GND")
		)
		(pad "BW78" smd circle
			(at 30.382464 1.824228)
			(size 0.4318 0.4318)
			(layers "F.Cu" "F.Mask" "F.Paste")
			(net "GND")
		)
		(pad "BW80" smd circle
			(at 32.099504 1.824228)
			(size 0.4318 0.4318)
			(layers "F.Cu" "F.Mask" "F.Paste")
			(net "GND")
		)
		(pad "BW82" smd circle
			(at 33.816544 1.824228)
			(size 0.4318 0.4318)
			(layers "F.Cu" "F.Mask" "F.Paste")
			(net "GND")
		)
		(pad "BW84" smd custom
			(at 35.533584 1.824228 270)
			(size 0.10795 0.10795)
			(layers "F.Cu" "F.Mask" "F.Paste")
			(net "PVCCIN_CPU1")
			(options
				(clearance outline)
				(anchor circle)
			)
			(primitives
				(gr_poly
					(pts
						(arc
							(start 0.2159 -0.0381)
							(mid 0 -0.254)
							(end -0.2159 -0.0381)
						)
						(arc
							(start -0.2159 0.0381)
							(mid 0 0.254)
							(end 0.2159 0.0381)
						)
					)
					(width 0)
					(fill yes)
				)
			)
		)
		(pad "BY3" smd custom
			(at -35.533584 4.119372 90)
			(size 0.10795 0.10795)
			(layers "F.Cu" "F.Mask" "F.Paste")
			(net "TP_P3E_CPU1_PE2_RSR_TXP<9>")
			(options
				(clearance outline)
				(anchor circle)
			)
			(primitives
				(gr_poly
					(pts
						(arc
							(start 0.2159 -0.0381)
							(mid 0 -0.254)
							(end -0.2159 -0.0381)
						)
						(arc
							(start -0.2159 0.0381)
							(mid 0 0.254)
							(end 0.2159 0.0381)
						)
					)
					(width 0)
					(fill yes)
				)
			)
		)
		(pad "BY5" smd circle
			(at -33.816544 4.119372)
			(size 0.4318 0.4318)
			(layers "F.Cu" "F.Mask" "F.Paste")
			(net "TP_P3E_CPU1_PE2_RSR_TXP<10>")
		)
		(pad "BY7" smd circle
			(at -32.099504 4.119372)
			(size 0.4318 0.4318)
			(layers "F.Cu" "F.Mask" "F.Paste")
			(net "TP_P3E_CPU1_PE2_RSR_RXN<9>")
		)
		(pad "BY9" smd circle
			(at -30.382464 4.119372)
			(size 0.4318 0.4318)
			(layers "F.Cu" "F.Mask" "F.Paste")
			(net "TP_P3E_CPU1_PE2_RSR_RXN<8>")
		)
		(pad "BY11" smd circle
			(at -28.665424 4.119372)
			(size 0.4318 0.4318)
			(layers "F.Cu" "F.Mask" "F.Paste")
			(net "GND")
		)
		(pad "BY13" smd circle
			(at -26.948384 4.119372)
			(size 0.4318 0.4318)
			(layers "F.Cu" "F.Mask" "F.Paste")
			(net "GND")
		)
		(pad "BY15" smd circle
			(at -25.231598 4.119372)
			(size 0.4318 0.4318)
			(layers "F.Cu" "F.Mask" "F.Paste")
			(net "GND")
		)
		(pad "BY17" smd circle
			(at -23.514558 4.119372)
			(size 0.4318 0.4318)
			(layers "F.Cu" "F.Mask" "F.Paste")
			(net "GND")
		)
		(pad "BY19" smd circle
			(at -21.797518 4.119372)
			(size 0.4318 0.4318)
			(layers "F.Cu" "F.Mask" "F.Paste")
			(net "PVCCMCP_CPU1")
		)
		(pad "BY21" smd circle
			(at -20.080478 4.119372)
			(size 0.4318 0.4318)
			(layers "F.Cu" "F.Mask" "F.Paste")
			(net "JTAG_MCP_CPU1_TDI")
		)
		(pad "BY23" smd circle
			(at -18.363438 4.119372)
			(size 0.4318 0.4318)
			(layers "F.Cu" "F.Mask" "F.Paste")
			(net "GND")
		)
		(pad "BY25" smd circle
			(at -16.646398 4.119372)
			(size 0.4318 0.4318)
			(layers "F.Cu" "F.Mask" "F.Paste")
			(net "TP_CPU1_RSVD_119")
		)
		(pad "BY27" smd circle
			(at -14.929612 4.119372)
			(size 0.4318 0.4318)
			(layers "F.Cu" "F.Mask" "F.Paste")
			(net "P1V8_MCP_CPU1")
		)
		(pad "BY61" smd circle
			(at 15.787878 2.319274)
			(size 0.4318 0.4318)
			(layers "F.Cu" "F.Mask" "F.Paste")
			(net "PVCCIN_CPU1")
		)
		(pad "BY63" smd circle
			(at 17.504918 2.319274)
			(size 0.4318 0.4318)
			(layers "F.Cu" "F.Mask" "F.Paste")
			(net "GND")
		)
		(pad "BY65" smd circle
			(at 19.221958 2.319274)
			(size 0.4318 0.4318)
			(layers "F.Cu" "F.Mask" "F.Paste")
			(net "GND")
		)
		(pad "BY67" smd circle
			(at 20.938998 2.319274)
			(size 0.4318 0.4318)
			(layers "F.Cu" "F.Mask" "F.Paste")
			(net "GND")
		)
		(pad "BY69" smd circle
			(at 22.656038 2.319274)
			(size 0.4318 0.4318)
			(layers "F.Cu" "F.Mask" "F.Paste")
			(net "GND")
		)
		(pad "BY71" smd circle
			(at 24.373078 2.319274)
			(size 0.4318 0.4318)
			(layers "F.Cu" "F.Mask" "F.Paste")
			(net "GND")
		)
		(pad "BY73" smd circle
			(at 26.090118 2.319274)
			(size 0.4318 0.4318)
			(layers "F.Cu" "F.Mask" "F.Paste")
			(net "PVCCIN_CPU1")
		)
		(pad "BY75" smd circle
			(at 27.806904 2.319274)
			(size 0.4318 0.4318)
			(layers "F.Cu" "F.Mask" "F.Paste")
			(net "PVCCIN_CPU1")
		)
		(pad "BY77" smd circle
			(at 29.523944 2.319274)
			(size 0.4318 0.4318)
			(layers "F.Cu" "F.Mask" "F.Paste")
			(net "PVCCIN_CPU1")
		)
		(pad "BY79" smd circle
			(at 31.240984 2.319274)
			(size 0.4318 0.4318)
			(layers "F.Cu" "F.Mask" "F.Paste")
			(net "PVCCIN_CPU1")
		)
		(pad "BY81" smd circle
			(at 32.958024 2.319274)
			(size 0.4318 0.4318)
			(layers "F.Cu" "F.Mask" "F.Paste")
			(net "PVCCIN_CPU1")
		)
		(pad "BY83" smd circle
			(at 34.675064 2.319274)
			(size 0.4318 0.4318)
			(layers "F.Cu" "F.Mask" "F.Paste")
			(net "PVCCIN_CPU1")
		)
		(pad "C4" smd custom
			(at -34.675064 -24.112474 45)
			(size 0.10795 0.10795)
			(layers "F.Cu" "F.Mask" "F.Paste")
			(net "GND")
			(options
				(clearance outline)
				(anchor circle)
			)
			(primitives
				(gr_poly
					(pts
						(arc
							(start 0.2159 -0.0381)
							(mid 0 -0.254)
							(end -0.2159 -0.0381)
						)
						(arc
							(start -0.2159 0.0381)
							(mid 0 0.254)
							(end 0.2159 0.0381)
						)
					)
					(width 0)
					(fill yes)
				)
			)
		)
		(pad "C6" smd custom
			(at -32.958024 -24.112474)
			(size 0.10795 0.10795)
			(layers "F.Cu" "F.Mask" "F.Paste")
			(net "TP_CPU1_RSVD_291")
			(options
				(clearance outline)
				(anchor circle)
			)
			(primitives
				(gr_poly
					(pts
						(arc
							(start 0.2159 -0.0381)
							(mid 0 -0.254)
							(end -0.2159 -0.0381)
						)
						(arc
							(start -0.2159 0.0381)
							(mid 0 0.254)
							(end 0.2159 0.0381)
						)
					)
					(width 0)
					(fill yes)
				)
			)
		)
		(pad "C8" smd circle
			(at -31.240984 -24.112474)
			(size 0.4318 0.4318)
			(layers "F.Cu" "F.Mask" "F.Paste")
			(net "GND")
		)
		(pad "C10" smd circle
			(at -29.523944 -24.112474)
			(size 0.4318 0.4318)
			(layers "F.Cu" "F.Mask" "F.Paste")
			(net "GND")
		)
		(pad "C12" smd circle
			(at -27.806904 -24.112474)
			(size 0.4318 0.4318)
			(layers "F.Cu" "F.Mask" "F.Paste")
			(net "GND")
		)
		(pad "C14" smd circle
			(at -26.090118 -24.112474)
			(size 0.4318 0.4318)
			(layers "F.Cu" "F.Mask" "F.Paste")
			(net "GND")
		)
		(pad "C16" smd circle
			(at -24.373078 -24.112474)
			(size 0.4318 0.4318)
			(layers "F.Cu" "F.Mask" "F.Paste")
			(net "GND")
		)
		(pad "C18" smd custom
			(at -22.656038 -24.112474)
			(size 0.10795 0.10795)
			(layers "F.Cu" "F.Mask" "F.Paste")
			(net "TP_CPU1_RSVD_290")
			(options
				(clearance outline)
				(anchor circle)
			)
			(primitives
				(gr_poly
					(pts
						(arc
							(start 0.2159 -0.0381)
							(mid 0 -0.254)
							(end -0.2159 -0.0381)
						)
						(arc
							(start -0.2159 0.0381)
							(mid 0 0.254)
							(end 0.2159 0.0381)
						)
					)
					(width 0)
					(fill yes)
				)
			)
		)
		(pad "C24" smd custom
			(at -17.504918 -24.112474)
			(size 0.10795 0.10795)
			(layers "F.Cu" "F.Mask" "F.Paste")
			(net "TP_CPU1_RSVD_289")
			(options
				(clearance outline)
				(anchor circle)
			)
			(primitives
				(gr_poly
					(pts
						(arc
							(start 0.2159 -0.0381)
							(mid 0 -0.254)
							(end -0.2159 -0.0381)
						)
						(arc
							(start -0.2159 0.0381)
							(mid 0 0.254)
							(end 0.2159 0.0381)
						)
					)
					(width 0)
					(fill yes)
				)
			)
		)
		(pad "C26" smd circle
			(at -15.787878 -24.112474)
			(size 0.4318 0.4318)
			(layers "F.Cu" "F.Mask" "F.Paste")
			(net "M_H_DQ<50>")
		)
		(pad "C28" smd circle
			(at -14.071092 -24.112474)
			(size 0.4318 0.4318)
			(layers "F.Cu" "F.Mask" "F.Paste")
			(net "M_H_DQS_DP<15>")
		)
		(pad "C30" smd circle
			(at -12.354052 -24.112474)
			(size 0.4318 0.4318)
			(layers "F.Cu" "F.Mask" "F.Paste")
			(net "M_H_DQ<48>")
		)
		(pad "C32" smd circle
			(at -10.637012 -24.112474)
			(size 0.4318 0.4318)
			(layers "F.Cu" "F.Mask" "F.Paste")
			(net "M_H_DQ<42>")
		)
		(pad "C34" smd circle
			(at -8.919972 -24.112474)
			(size 0.4318 0.4318)
			(layers "F.Cu" "F.Mask" "F.Paste")
			(net "M_H_DQS_DP<14>")
		)
		(pad "C36" smd circle
			(at -7.202932 -24.112474)
			(size 0.4318 0.4318)
			(layers "F.Cu" "F.Mask" "F.Paste")
			(net "M_H_DQ<40>")
		)
		(pad "C38" smd circle
			(at -5.485892 -24.112474)
			(size 0.4318 0.4318)
			(layers "F.Cu" "F.Mask" "F.Paste")
			(net "M_G_DQ<34>")
		)
		(pad "C40" smd circle
			(at -3.769106 -24.112474)
			(size 0.4318 0.4318)
			(layers "F.Cu" "F.Mask" "F.Paste")
			(net "M_G_DQS_DP<13>")
		)
		(pad "C42" smd circle
			(at -2.052066 -24.112474)
			(size 0.4318 0.4318)
			(layers "F.Cu" "F.Mask" "F.Paste")
			(net "M_G_DQ<32>")
		)
		(pad "C46" smd custom
			(at 2.910586 -25.912572 45)
			(size 0.10795 0.10795)
			(layers "F.Cu" "F.Mask" "F.Paste")
			(net "PVDDQ_GHJ")
			(options
				(clearance outline)
				(anchor circle)
			)
			(primitives
				(gr_poly
					(pts
						(arc
							(start 0.2159 -0.0381)
							(mid 0 -0.254)
							(end -0.2159 -0.0381)
						)
						(arc
							(start -0.2159 0.0381)
							(mid 0 0.254)
							(end 0.2159 0.0381)
						)
					)
					(width 0)
					(fill yes)
				)
			)
		)
		(pad "C48" smd circle
			(at 4.627626 -25.912572)
			(size 0.4318 0.4318)
			(layers "F.Cu" "F.Mask" "F.Paste")
			(net "M_G_ODT<1>")
		)
		(pad "C50" smd circle
			(at 6.344412 -25.912572)
			(size 0.4318 0.4318)
			(layers "F.Cu" "F.Mask" "F.Paste")
			(net "M_G_ODT<0>")
		)
		(pad "C52" smd circle
			(at 8.061452 -25.912572)
			(size 0.4318 0.4318)
			(layers "F.Cu" "F.Mask" "F.Paste")
			(net "M_G_BA<0>")
		)
		(pad "C54" smd circle
			(at 9.778492 -25.912572)
			(size 0.4318 0.4318)
			(layers "F.Cu" "F.Mask" "F.Paste")
			(net "M_G_CLK_DN<1>")
		)
		(pad "C56" smd circle
			(at 11.495532 -25.912572)
			(size 0.4318 0.4318)
			(layers "F.Cu" "F.Mask" "F.Paste")
			(net "M_G_CLK_DN<3>")
		)
		(pad "C58" smd circle
			(at 13.212572 -25.912572)
			(size 0.4318 0.4318)
			(layers "F.Cu" "F.Mask" "F.Paste")
			(net "M_G_MA<3>")
		)
		(pad "C60" smd circle
			(at 14.929612 -25.912572)
			(size 0.4318 0.4318)
			(layers "F.Cu" "F.Mask" "F.Paste")
			(net "M_G_MA<8>")
		)
		(pad "C62" smd circle
			(at 16.646398 -25.912572)
			(size 0.4318 0.4318)
			(layers "F.Cu" "F.Mask" "F.Paste")
			(net "M_G_CKE<0>")
		)
		(pad "C64" smd custom
			(at 18.363438 -25.912572)
			(size 0.10795 0.10795)
			(layers "F.Cu" "F.Mask" "F.Paste")
			(net "M_G_CKE<1>")
			(options
				(clearance outline)
				(anchor circle)
			)
			(primitives
				(gr_poly
					(pts
						(arc
							(start 0.2159 -0.0381)
							(mid 0 -0.254)
							(end -0.2159 -0.0381)
						)
						(arc
							(start -0.2159 0.0381)
							(mid 0 0.254)
							(end 0.2159 0.0381)
						)
					)
					(width 0)
					(fill yes)
				)
			)
		)
		(pad "C72" smd circle
			(at 25.231598 -25.912572)
			(size 0.4318 0.4318)
			(layers "F.Cu" "F.Mask" "F.Paste")
			(net "M_H_DQ<30>")
		)
		(pad "C74" smd circle
			(at 26.948384 -25.912572)
			(size 0.4318 0.4318)
			(layers "F.Cu" "F.Mask" "F.Paste")
			(net "M_H_DQ<25>")
		)
		(pad "C76" smd circle
			(at 28.665424 -25.912572)
			(size 0.4318 0.4318)
			(layers "F.Cu" "F.Mask" "F.Paste")
			(net "GND")
		)
		(pad "C78" smd circle
			(at 30.382464 -25.912572)
			(size 0.4318 0.4318)
			(layers "F.Cu" "F.Mask" "F.Paste")
			(net "GND")
		)
		(pad "C80" smd custom
			(at 32.099504 -25.912572 315)
			(size 0.10795 0.10795)
			(layers "F.Cu" "F.Mask" "F.Paste")
			(net "GND")
			(options
				(clearance outline)
				(anchor circle)
			)
			(primitives
				(gr_poly
					(pts
						(arc
							(start 0.2159 -0.0381)
							(mid 0 -0.254)
							(end -0.2159 -0.0381)
						)
						(arc
							(start -0.2159 0.0381)
							(mid 0 0.254)
							(end 0.2159 0.0381)
						)
					)
					(width 0)
					(fill yes)
				)
			)
		)
		(pad "C82" smd custom
			(at 33.816544 -25.912572 315)
			(size 0.10795 0.10795)
			(layers "F.Cu" "F.Mask" "F.Paste")
			(net "TP_CPU1_RSVD_288")
			(options
				(clearance outline)
				(anchor circle)
			)
			(primitives
				(gr_poly
					(pts
						(arc
							(start 0.2159 -0.0381)
							(mid 0 -0.254)
							(end -0.2159 -0.0381)
						)
						(arc
							(start -0.2159 0.0381)
							(mid 0 0.254)
							(end 0.2159 0.0381)
						)
					)
					(width 0)
					(fill yes)
				)
			)
		)
		(pad "CA2" smd custom
			(at -36.392104 4.614926 90)
			(size 0.10795 0.10795)
			(layers "F.Cu" "F.Mask" "F.Paste")
			(net "GND")
			(options
				(clearance outline)
				(anchor circle)
			)
			(primitives
				(gr_poly
					(pts
						(arc
							(start 0.2159 -0.0381)
							(mid 0 -0.254)
							(end -0.2159 -0.0381)
						)
						(arc
							(start -0.2159 0.0381)
							(mid 0 0.254)
							(end 0.2159 0.0381)
						)
					)
					(width 0)
					(fill yes)
				)
			)
		)
		(pad "CA4" smd circle
			(at -34.675064 4.614926)
			(size 0.4318 0.4318)
			(layers "F.Cu" "F.Mask" "F.Paste")
			(net "TP_P3E_CPU1_PE2_RSR_TXN<10>")
		)
		(pad "CA6" smd circle
			(at -32.958024 4.614926)
			(size 0.4318 0.4318)
			(layers "F.Cu" "F.Mask" "F.Paste")
			(net "GND")
		)
		(pad "CA8" smd circle
			(at -31.240984 4.614926)
			(size 0.4318 0.4318)
			(layers "F.Cu" "F.Mask" "F.Paste")
			(net "GND")
		)
		(pad "CA10" smd circle
			(at -29.523944 4.614926)
			(size 0.4318 0.4318)
			(layers "F.Cu" "F.Mask" "F.Paste")
			(net "GND")
		)
		(pad "CA12" smd circle
			(at -27.806904 4.614926)
			(size 0.4318 0.4318)
			(layers "F.Cu" "F.Mask" "F.Paste")
			(net "TP_CPU1_UPI2_RSVD_DP21")
		)
		(pad "CA14" smd circle
			(at -26.090118 4.614926)
			(size 0.4318 0.4318)
			(layers "F.Cu" "F.Mask" "F.Paste")
			(net "GND")
		)
		(pad "CA16" smd circle
			(at -24.373078 4.614926)
			(size 0.4318 0.4318)
			(layers "F.Cu" "F.Mask" "F.Paste")
			(net "GND")
		)
		(pad "CA18" smd circle
			(at -22.656038 4.614926)
			(size 0.4318 0.4318)
			(layers "F.Cu" "F.Mask" "F.Paste")
			(net "GND")
		)
		(pad "CA20" smd circle
			(at -20.938998 4.614926)
			(size 0.4318 0.4318)
			(layers "F.Cu" "F.Mask" "F.Paste")
			(net "GND")
		)
		(pad "CA22" smd circle
			(at -19.221958 4.614926)
			(size 0.4318 0.4318)
			(layers "F.Cu" "F.Mask" "F.Paste")
			(net "PVCCMCP_CPU1")
		)
		(pad "CA24" smd circle
			(at -17.504918 4.614926)
			(size 0.4318 0.4318)
			(layers "F.Cu" "F.Mask" "F.Paste")
			(net "TP_CPU1_RSVD_117")
		)
		(pad "CA26" smd circle
			(at -15.787878 4.614926)
			(size 0.4318 0.4318)
			(layers "F.Cu" "F.Mask" "F.Paste")
			(net "GND")
		)
		(pad "CA60" smd circle
			(at 14.929612 2.814828)
			(size 0.508 0.508)
			(layers "F.Cu" "F.Mask" "F.Paste")
			(net "PVCCIN_CPU1")
		)
		(pad "CA62" smd circle
			(at 16.646398 2.814828)
			(size 0.4318 0.4318)
			(layers "F.Cu" "F.Mask" "F.Paste")
			(net "PVCCIN_CPU1")
		)
		(pad "CA64" smd circle
			(at 18.363438 2.814828)
			(size 0.4318 0.4318)
			(layers "F.Cu" "F.Mask" "F.Paste")
			(net "GND")
		)
		(pad "CA66" smd circle
			(at 20.080478 2.814828)
			(size 0.4318 0.4318)
			(layers "F.Cu" "F.Mask" "F.Paste")
			(net "GND")
		)
		(pad "CA68" smd circle
			(at 21.797518 2.814828)
			(size 0.4318 0.4318)
			(layers "F.Cu" "F.Mask" "F.Paste")
			(net "GND")
		)
		(pad "CA70" smd circle
			(at 23.514558 2.814828)
			(size 0.4318 0.4318)
			(layers "F.Cu" "F.Mask" "F.Paste")
			(net "GND")
		)
		(pad "CA72" smd circle
			(at 25.231598 2.814828)
			(size 0.4318 0.4318)
			(layers "F.Cu" "F.Mask" "F.Paste")
			(net "PVCCIN_CPU1")
		)
		(pad "CA74" smd circle
			(at 26.948384 2.814828)
			(size 0.4318 0.4318)
			(layers "F.Cu" "F.Mask" "F.Paste")
			(net "PVCCIN_CPU1")
		)
		(pad "CA76" smd circle
			(at 28.665424 2.814828)
			(size 0.4318 0.4318)
			(layers "F.Cu" "F.Mask" "F.Paste")
			(net "PVCCIN_CPU1")
		)
		(pad "CA78" smd circle
			(at 30.382464 2.814828)
			(size 0.4318 0.4318)
			(layers "F.Cu" "F.Mask" "F.Paste")
			(net "PVCCIN_CPU1")
		)
		(pad "CA80" smd circle
			(at 32.099504 2.814828)
			(size 0.4318 0.4318)
			(layers "F.Cu" "F.Mask" "F.Paste")
			(net "PVCCIN_CPU1")
		)
		(pad "CA82" smd circle
			(at 33.816544 2.814828)
			(size 0.4318 0.4318)
			(layers "F.Cu" "F.Mask" "F.Paste")
			(net "PVCCIN_CPU1")
		)
	)
)
